(kicad_pcb
	(version 20260206)
	(generator "pcbnew")
	(generator_version "10.0")
	(general
		(thickness 1.6)
		(legacy_teardrops no)
	)
	(paper "A4")
	(title_block
		(title "fcb — Lightning_FCB_BRD.brd")
		(comment 1 "Lightning (Wiwynn / Facebook NVMe JBOF) / footprints 138-142 of 495")
	)
	(layers
		(0 "F.Cu" signal "TOP")
		(4 "In1.Cu" signal "L2GND")
		(6 "In2.Cu" signal "L3VCC")
		(2 "B.Cu" signal "BOTTOM")
		(9 "F.Adhes" user "F.Adhesive")
		(11 "B.Adhes" user "B.Adhesive")
		(13 "F.Paste" user "Package Geometry/Pastemask Top")
		(15 "B.Paste" user "Package Geometry/Pastemask Bottom")
		(5 "F.SilkS" user "Ref Des/Silkscreen Top")
		(7 "B.SilkS" user "Ref Des/Silkscreen Bottom")
		(1 "F.Mask" user "Board Geometry/Soldermask Top")
		(3 "B.Mask" user "Board Geometry/Soldermask Bottom")
		(17 "Dwgs.User" user "User.Drawings")
		(19 "Cmts.User" user "User.Comments")
		(21 "Eco1.User" user "User.Eco1")
		(23 "Eco2.User" user "User.Eco2")
		(25 "Edge.Cuts" user "Board Geometry/Outline")
		(27 "Margin" user)
		(31 "F.CrtYd" user "Package Geometry/Place Bound Top")
		(29 "B.CrtYd" user "Package Geometry/Place Bound Bottom")
		(35 "F.Fab" user "Ref Des/Assembly Top")
		(33 "B.Fab" user "Ref Des/Assembly Bottom")
	)
	(footprint ""
		(layer "F.Cu")
		(at 13.923518 -230.153972 180)
		(property "Reference" "Q5"
			(at 0 0 180)
			(layer "F.SilkS")
			(hide yes)
			(effects
				(font
					(size 1.27 1.27)
				)
			)
		)
		(property "Value" "PMBS3904-1-GP"
			(at 0 -9.0932 180)
			(unlocked yes)
			(layer "F.Fab")
			(hide yes)
			(effects
				(font
					(size 1.016 1.016)
					(thickness 0.1524)
				)
			)
		)
		(property "Device Type" "SOT-23-10H44"
			(at 0 -10.6172 180)
			(unlocked yes)
			(layer "F.Fab")
			(hide yes)
			(effects
				(font
					(size 1.016 1.016)
					(thickness 0.1524)
				)
			)
		)
		(duplicate_pad_numbers_are_jumpers no)
		(fp_line
			(start 1.651 1.778)
			(end 1.651 -1.778)
			(stroke
				(width 0.1524)
				(type default)
			)
			(layer "F.SilkS")
		)
		(fp_line
			(start 1.651 -1.778)
			(end -1.651 -1.778)
			(stroke
				(width 0.1524)
				(type default)
			)
			(layer "F.SilkS")
		)
		(fp_line
			(start -0.635 1.8796)
			(end -1.7526 1.8796)
			(stroke
				(width 0.3302)
				(type default)
			)
			(layer "F.SilkS")
		)
		(fp_line
			(start -0.71628 2.15265)
			(end -1.26492 2.15265)
			(stroke
				(width 0.0127)
				(type default)
			)
			(layer "F.SilkS")
		)
		(fp_line
			(start -0.719074 2.145538)
			(end -1.265936 2.14122)
			(stroke
				(width 0.0127)
				(type default)
			)
			(layer "F.SilkS")
		)
		(fp_line
			(start -0.9906 1.86309)
			(end -0.701294 2.15265)
			(stroke
				(width 0.0127)
				(type default)
			)
			(layer "F.SilkS")
		)
		(fp_line
			(start -0.994156 1.8669)
			(end -0.987044 1.8669)
			(stroke
				(width 0.0127)
				(type default)
			)
			(layer "F.SilkS")
		)
		(fp_line
			(start -1.003808 1.876552)
			(end -0.977646 1.876552)
			(stroke
				(width 0.0127)
				(type default)
			)
			(layer "F.SilkS")
		)
		(fp_line
			(start -1.013206 1.88595)
			(end -0.967994 1.88595)
			(stroke
				(width 0.0127)
				(type default)
			)
			(layer "F.SilkS")
		)
		(fp_line
			(start -1.022858 1.895602)
			(end -0.958596 1.895602)
			(stroke
				(width 0.0127)
				(type default)
			)
			(layer "F.SilkS")
		)
		(fp_line
			(start -1.032256 1.905)
			(end -0.948944 1.905)
			(stroke
				(width 0.0127)
				(type default)
			)
			(layer "F.SilkS")
		)
		(fp_line
			(start -1.041908 1.914652)
			(end -0.939546 1.914652)
			(stroke
				(width 0.0127)
				(type default)
			)
			(layer "F.SilkS")
		)
		(fp_line
			(start -1.051306 1.92405)
			(end -0.929894 1.92405)
			(stroke
				(width 0.0127)
				(type default)
			)
			(layer "F.SilkS")
		)
		(fp_line
			(start -1.060958 1.933702)
			(end -0.920496 1.933702)
			(stroke
				(width 0.0127)
				(type default)
			)
			(layer "F.SilkS")
		)
		(fp_line
			(start -1.070356 1.9431)
			(end -0.910844 1.9431)
			(stroke
				(width 0.0127)
				(type default)
			)
			(layer "F.SilkS")
		)
		(fp_line
			(start -1.080008 1.952752)
			(end -0.901446 1.952752)
			(stroke
				(width 0.0127)
				(type default)
			)
			(layer "F.SilkS")
		)
		(fp_line
			(start -1.089406 1.96215)
			(end -0.891794 1.96215)
			(stroke
				(width 0.0127)
				(type default)
			)
			(layer "F.SilkS")
		)
		(fp_line
			(start -1.099058 1.971802)
			(end -0.882396 1.971802)
			(stroke
				(width 0.0127)
				(type default)
			)
			(layer "F.SilkS")
		)
		(fp_line
			(start -1.108456 1.9812)
			(end -0.872744 1.9812)
			(stroke
				(width 0.0127)
				(type default)
			)
			(layer "F.SilkS")
		)
		(fp_line
			(start -1.118108 1.990852)
			(end -0.863346 1.990852)
			(stroke
				(width 0.0127)
				(type default)
			)
			(layer "F.SilkS")
		)
		(fp_line
			(start -1.127506 2.00025)
			(end -0.853694 2.00025)
			(stroke
				(width 0.0127)
				(type default)
			)
			(layer "F.SilkS")
		)
		(fp_line
			(start -1.137158 2.009902)
			(end -0.844296 2.009902)
			(stroke
				(width 0.0127)
				(type default)
			)
			(layer "F.SilkS")
		)
		(fp_line
			(start -1.146556 2.0193)
			(end -0.834644 2.0193)
			(stroke
				(width 0.0127)
				(type default)
			)
			(layer "F.SilkS")
		)
		(fp_line
			(start -1.156208 2.028952)
			(end -0.825246 2.028952)
			(stroke
				(width 0.0127)
				(type default)
			)
			(layer "F.SilkS")
		)
		(fp_line
			(start -1.165606 2.03835)
			(end -0.815594 2.03835)
			(stroke
				(width 0.0127)
				(type default)
			)
			(layer "F.SilkS")
		)
		(fp_line
			(start -1.175258 2.048002)
			(end -0.806196 2.048002)
			(stroke
				(width 0.0127)
				(type default)
			)
			(layer "F.SilkS")
		)
		(fp_line
			(start -1.184656 2.0574)
			(end -0.796544 2.0574)
			(stroke
				(width 0.0127)
				(type default)
			)
			(layer "F.SilkS")
		)
		(fp_line
			(start -1.194308 2.067052)
			(end -0.787146 2.067052)
			(stroke
				(width 0.0127)
				(type default)
			)
			(layer "F.SilkS")
		)
		(fp_line
			(start -1.203706 2.07645)
			(end -0.777494 2.07645)
			(stroke
				(width 0.0127)
				(type default)
			)
			(layer "F.SilkS")
		)
		(fp_line
			(start -1.213358 2.086102)
			(end -0.768096 2.086102)
			(stroke
				(width 0.0127)
				(type default)
			)
			(layer "F.SilkS")
		)
		(fp_line
			(start -1.222756 2.0955)
			(end -0.758444 2.0955)
			(stroke
				(width 0.0127)
				(type default)
			)
			(layer "F.SilkS")
		)
		(fp_line
			(start -1.232408 2.105152)
			(end -0.749046 2.105152)
			(stroke
				(width 0.0127)
				(type default)
			)
			(layer "F.SilkS")
		)
		(fp_line
			(start -1.241806 2.11455)
			(end -0.739394 2.11455)
			(stroke
				(width 0.0127)
				(type default)
			)
			(layer "F.SilkS")
		)
		(fp_line
			(start -1.251458 2.124202)
			(end -0.729996 2.124202)
			(stroke
				(width 0.0127)
				(type default)
			)
			(layer "F.SilkS")
		)
		(fp_line
			(start -1.260856 2.1336)
			(end -0.720344 2.1336)
			(stroke
				(width 0.0127)
				(type default)
			)
			(layer "F.SilkS")
		)
		(fp_line
			(start -1.279144 2.15265)
			(end -0.701294 2.15265)
			(stroke
				(width 0.0127)
				(type default)
			)
			(layer "F.SilkS")
		)
		(fp_line
			(start -1.279398 2.152142)
			(end -0.9906 1.86309)
			(stroke
				(width 0.0127)
				(type default)
			)
			(layer "F.SilkS")
		)
		(fp_line
			(start -1.651 1.778)
			(end 1.651 1.778)
			(stroke
				(width 0.1524)
				(type default)
			)
			(layer "F.SilkS")
		)
		(fp_line
			(start -1.651 -1.778)
			(end -1.651 1.778)
			(stroke
				(width 0.1524)
				(type default)
			)
			(layer "F.SilkS")
		)
		(fp_line
			(start -1.7526 1.8796)
			(end -1.7526 0.9906)
			(stroke
				(width 0.3302)
				(type default)
			)
			(layer "F.SilkS")
		)
		(fp_poly
			(pts
				(xy -1.285748 2.159) (xy -1.285748 1.8796) (xy -1.778 1.8796) (xy -1.778 -1.8796) (xy 1.778 -1.8796)
				(xy 1.778 1.8796) (xy -0.694944 1.8796) (xy -0.694944 2.159)
			)
			(stroke
				(width 0)
				(type default)
			)
			(fill no)
			(layer "F.CrtYd")
		)
		(fp_poly
			(pts
				(xy -1.285748 2.159) (xy -1.285748 1.8796) (xy -1.778 1.8796) (xy -1.778 -1.8796) (xy 1.778 -1.8796)
				(xy 1.778 1.8796) (xy -0.694944 1.8796) (xy -0.694944 2.159)
			)
			(stroke
				(width 0)
				(type default)
			)
			(fill no)
			(layer "F.Fab")
		)
		(pad "1" smd rect
			(at -0.98425 0.9525 180)
			(size 0.762 1.143)
			(layers "F.Cu" "F.Mask" "F.Paste")
			(net "LED_DR_LED3_B")
		)
		(pad "2" smd rect
			(at 0.98425 0.9525 180)
			(size 0.762 1.143)
			(layers "F.Cu" "F.Mask" "F.Paste")
			(net "GND")
		)
		(pad "3" smd rect
			(at 0 -0.9525 180)
			(size 0.762 1.143)
			(layers "F.Cu" "F.Mask" "F.Paste")
			(net "LED_DR_LED3_BLUE")
		)
	)
	(footprint ""
		(layer "F.Cu")
		(at 17.2466 -400.2024)
		(property "Reference" "PQ13"
			(at 0 0 0)
			(layer "F.SilkS")
			(hide yes)
			(effects
				(font
					(size 1.27 1.27)
				)
			)
		)
		(property "Value" "PH0925CL-GP"
			(at -4.2799 -0.4572 0)
			(unlocked yes)
			(layer "F.Fab")
			(hide yes)
			(effects
				(font
					(size 1.016 1.016)
					(thickness 0.1524)
				)
			)
		)
		(property "Device Type" "LFPAK-5PH48-U"
			(at -4.2799 -1.9812 0)
			(unlocked yes)
			(layer "F.Fab")
			(hide yes)
			(effects
				(font
					(size 1.016 1.016)
					(thickness 0.1524)
				)
			)
		)
		(duplicate_pad_numbers_are_jumpers no)
		(fp_line
			(start -2.7559 -6.5532)
			(end -2.7559 1.0668)
			(stroke
				(width 0.1524)
				(type default)
			)
			(layer "F.SilkS")
		)
		(fp_line
			(start -2.7559 1.0668)
			(end 2.7559 1.0668)
			(stroke
				(width 0.1524)
				(type default)
			)
			(layer "F.SilkS")
		)
		(fp_line
			(start -1.7272 1.1684)
			(end -2.1082 1.1684)
			(stroke
				(width 0.3302)
				(type default)
			)
			(layer "F.SilkS")
		)
		(fp_line
			(start 2.7559 -6.5532)
			(end -2.7559 -6.5532)
			(stroke
				(width 0.1524)
				(type default)
			)
			(layer "F.SilkS")
		)
		(fp_line
			(start 2.7559 1.0668)
			(end 2.7559 -6.5532)
			(stroke
				(width 0.1524)
				(type default)
			)
			(layer "F.SilkS")
		)
		(fp_poly
			(pts
				(xy -2.3368 1.5748) (xy -1.905 1.143) (xy -1.4732 1.5748)
			)
			(stroke
				(width 0)
				(type default)
			)
			(fill yes)
			(layer "F.SilkS")
		)
		(fp_poly
			(pts
				(xy -2.5019 -4.02971) (xy -0.3302 -4.02971) (xy -0.3302 -6.30301) (xy -2.5019 -6.30301)
			)
			(stroke
				(width 0)
				(type default)
			)
			(fill yes)
			(layer "F.Paste")
		)
		(fp_poly
			(pts
				(xy -2.5019 -1.09601) (xy -0.3302 -1.09601) (xy -0.3302 -3.36931) (xy -2.5019 -3.36931)
			)
			(stroke
				(width 0)
				(type default)
			)
			(fill yes)
			(layer "F.Paste")
		)
		(fp_poly
			(pts
				(xy 0.3302 -4.02971) (xy 2.5019 -4.02971) (xy 2.5019 -6.30301) (xy 0.3302 -6.30301)
			)
			(stroke
				(width 0)
				(type default)
			)
			(fill yes)
			(layer "F.Paste")
		)
		(fp_poly
			(pts
				(xy 0.3302 -1.09601) (xy 2.5019 -1.09601) (xy 2.5019 -3.36931) (xy 0.3302 -3.36931)
			)
			(stroke
				(width 0)
				(type default)
			)
			(fill yes)
			(layer "F.Paste")
		)
		(fp_rect
			(start -2.4511 0.3048)
			(end 2.4511 -5.6896)
			(stroke
				(width 0)
				(type default)
			)
			(fill no)
			(layer "F.CrtYd")
		)
		(fp_poly
			(pts
				(xy -3.0099 1.3208) (xy -3.0099 -6.8072) (xy 3.0099 -6.8072) (xy 3.0099 -1.016) (xy 2.4511 -1.016)
				(xy 2.4511 -5.6896) (xy -2.4511 -5.6896) (xy -2.4511 0.3048) (xy 2.4511 0.3048) (xy 2.4511 -1.0033)
				(xy 3.0099 -1.0033) (xy 3.0099 1.3208)
			)
			(stroke
				(width 0)
				(type default)
			)
			(fill no)
			(layer "F.CrtYd")
		)
		(fp_rect
			(start -3.0099 1.3208)
			(end 3.0099 -6.8072)
			(stroke
				(width 0)
				(type default)
			)
			(fill no)
			(layer "F.Fab")
		)
		(pad "1" smd rect
			(at -1.905 0)
			(size 0.762 1.6256)
			(layers "F.Cu" "F.Mask" "F.Paste")
			(net "P12V")
		)
		(pad "2" smd rect
			(at -0.635 0)
			(size 0.762 1.6256)
			(layers "F.Cu" "F.Mask" "F.Paste")
			(net "P12V")
		)
		(pad "3" smd rect
			(at 0.635 0)
			(size 0.762 1.6256)
			(layers "F.Cu" "F.Mask" "F.Paste")
			(net "P12V")
		)
		(pad "4" smd rect
			(at 1.905 0)
			(size 0.762 1.6256)
			(layers "F.Cu" "F.Mask" "F.Paste")
			(net "ADM1276_GATE_DRV0")
		)
		(pad "5" smd rect
			(at 0 -3.69951)
			(size 5.0038 5.207)
			(layers "F.Cu" "F.Mask" "F.Paste")
			(net "P12V_SENSE_TRACE")
		)
	)
	(footprint ""
		(layer "F.Cu")
		(at 37.70249 -165.513766 180)
		(property "Reference" "R2"
			(at 0 0 180)
			(layer "F.SilkS")
			(hide yes)
			(effects
				(font
					(size 1.27 1.27)
				)
			)
		)
		(property "Value" "0R2J-2-GP"
			(at 0.064008 -3.993896 180)
			(unlocked yes)
			(layer "F.Fab")
			(hide yes)
			(effects
				(font
					(size 1.016 1.016)
					(thickness 0.1524)
				)
			)
		)
		(property "Device Type" "R402H16"
			(at 0.064008 -5.517896 180)
			(unlocked yes)
			(layer "F.Fab")
			(hide yes)
			(effects
				(font
					(size 1.016 1.016)
					(thickness 0.1524)
				)
			)
		)
		(duplicate_pad_numbers_are_jumpers no)
		(fp_line
			(start 0.508 -0.9398)
			(end -0.508 -0.9398)
			(stroke
				(width 0.1524)
				(type default)
			)
			(layer "F.SilkS")
		)
		(fp_line
			(start -0.508 -0.9398)
			(end -0.508 0.9398)
			(stroke
				(width 0.1524)
				(type default)
			)
			(layer "F.SilkS")
		)
		(fp_rect
			(start -0.508 0.9398)
			(end 0.508 -0.9398)
			(stroke
				(width 0)
				(type default)
			)
			(fill no)
			(layer "F.CrtYd")
		)
		(fp_rect
			(start -0.508 0.9398)
			(end 0.508 -0.9398)
			(stroke
				(width 0)
				(type default)
			)
			(fill no)
			(layer "F.Fab")
		)
		(pad "1" smd custom
			(at 0 -0.4445 180)
			(size 0.1397 0.1397)
			(layers "F.Cu" "F.Mask" "F.Paste")
			(net "I2C_C_SCL_NCT7904")
			(options
				(clearance outline)
				(anchor circle)
			)
			(primitives
				(gr_poly
					(pts
						(arc
							(start -0.1778 -0.2794)
							(mid -0.249642 -0.249642)
							(end -0.2794 -0.1778)
						)
						(arc
							(start -0.2794 0.1778)
							(mid -0.249642 0.249642)
							(end -0.1778 0.2794)
						)
						(arc
							(start 0.1778 0.2794)
							(mid 0.249642 0.249642)
							(end 0.2794 0.1778)
						)
						(arc
							(start 0.2794 -0.1778)
							(mid 0.249642 -0.249642)
							(end 0.1778 -0.2794)
						)
					)
					(width 0)
					(fill yes)
				)
			)
		)
		(pad "2" smd custom
			(at 0 0.4445 180)
			(size 0.1397 0.1397)
			(layers "F.Cu" "F.Mask" "F.Paste")
			(net "I2C_C_SCL")
			(options
				(clearance outline)
				(anchor circle)
			)
			(primitives
				(gr_poly
					(pts
						(arc
							(start -0.1778 -0.2794)
							(mid -0.249642 -0.249642)
							(end -0.2794 -0.1778)
						)
						(arc
							(start -0.2794 0.1778)
							(mid -0.249642 0.249642)
							(end -0.1778 0.2794)
						)
						(arc
							(start 0.1778 0.2794)
							(mid 0.249642 0.249642)
							(end 0.2794 0.1778)
						)
						(arc
							(start 0.2794 -0.1778)
							(mid 0.249642 -0.249642)
							(end 0.1778 -0.2794)
						)
					)
					(width 0)
					(fill yes)
				)
			)
		)
	)
	(footprint ""
		(layer "F.Cu")
		(at 30.904434 -238.266224 180)
		(property "Reference" "R41"
			(at 0 0 180)
			(layer "F.SilkS")
			(hide yes)
			(effects
				(font
					(size 1.27 1.27)
				)
			)
		)
		(property "Value" "4K7R2J-2-GP"
			(at 0.064008 -3.993896 180)
			(unlocked yes)
			(layer "F.Fab")
			(hide yes)
			(effects
				(font
					(size 1.016 1.016)
					(thickness 0.1524)
				)
			)
		)
		(property "Device Type" "R402H16"
			(at 0.064008 -5.517896 180)
			(unlocked yes)
			(layer "F.Fab")
			(hide yes)
			(effects
				(font
					(size 1.016 1.016)
					(thickness 0.1524)
				)
			)
		)
		(duplicate_pad_numbers_are_jumpers no)
		(fp_line
			(start 0.508 -0.9398)
			(end -0.508 -0.9398)
			(stroke
				(width 0.1524)
				(type default)
			)
			(layer "F.SilkS")
		)
		(fp_line
			(start -0.508 -0.9398)
			(end -0.508 0.9398)
			(stroke
				(width 0.1524)
				(type default)
			)
			(layer "F.SilkS")
		)
		(fp_rect
			(start -0.508 0.9398)
			(end 0.508 -0.9398)
			(stroke
				(width 0)
				(type default)
			)
			(fill no)
			(layer "F.CrtYd")
		)
		(fp_rect
			(start -0.508 0.9398)
			(end 0.508 -0.9398)
			(stroke
				(width 0)
				(type default)
			)
			(fill no)
			(layer "F.Fab")
		)
		(pad "1" smd custom
			(at 0 -0.4445 180)
			(size 0.1397 0.1397)
			(layers "F.Cu" "F.Mask" "F.Paste")
			(net "P3V3")
			(options
				(clearance outline)
				(anchor circle)
			)
			(primitives
				(gr_poly
					(pts
						(arc
							(start -0.1778 -0.2794)
							(mid -0.249642 -0.249642)
							(end -0.2794 -0.1778)
						)
						(arc
							(start -0.2794 0.1778)
							(mid -0.249642 0.249642)
							(end -0.1778 0.2794)
						)
						(arc
							(start 0.1778 0.2794)
							(mid 0.249642 0.249642)
							(end 0.2794 0.1778)
						)
						(arc
							(start 0.2794 -0.1778)
							(mid 0.249642 -0.249642)
							(end 0.1778 -0.2794)
						)
					)
					(width 0)
					(fill yes)
				)
			)
		)
		(pad "2" smd custom
			(at 0 0.4445 180)
			(size 0.1397 0.1397)
			(layers "F.Cu" "F.Mask" "F.Paste")
			(net "FCB_EEPROM_A2")
			(options
				(clearance outline)
				(anchor circle)
			)
			(primitives
				(gr_poly
					(pts
						(arc
							(start -0.1778 -0.2794)
							(mid -0.249642 -0.249642)
							(end -0.2794 -0.1778)
						)
						(arc
							(start -0.2794 0.1778)
							(mid -0.249642 0.249642)
							(end -0.1778 0.2794)
						)
						(arc
							(start 0.1778 0.2794)
							(mid 0.249642 0.249642)
							(end 0.2794 0.1778)
						)
						(arc
							(start 0.2794 -0.1778)
							(mid 0.249642 -0.249642)
							(end 0.1778 -0.2794)
						)
					)
					(width 0)
					(fill yes)
				)
			)
		)
	)
	(footprint ""
		(layer "F.Cu")
		(at 20.9296 -174.3456 90)
		(property "Reference" "R22"
			(at 0 0 90)
			(layer "F.SilkS")
			(hide yes)
			(effects
				(font
					(size 1.27 1.27)
				)
			)
		)
		(property "Value" "4K7R2F-GP"
			(at 0.064008 -3.993896 90)
			(unlocked yes)
			(layer "F.Fab")
			(hide yes)
			(effects
				(font
					(size 1.016 1.016)
					(thickness 0.1524)
				)
			)
		)
		(property "Device Type" "R402H16"
			(at 0.064008 -5.517896 90)
			(unlocked yes)
			(layer "F.Fab")
			(hide yes)
			(effects
				(font
					(size 1.016 1.016)
					(thickness 0.1524)
				)
			)
		)
		(duplicate_pad_numbers_are_jumpers no)
		(fp_line
			(start 0.508 -0.9398)
			(end -0.508 -0.9398)
			(stroke
				(width 0.1524)
				(type default)
			)
			(layer "F.SilkS")
		)
		(fp_line
			(start -0.508 -0.9398)
			(end -0.508 0.9398)
			(stroke
				(width 0.1524)
				(type default)
			)
			(layer "F.SilkS")
		)
		(fp_rect
			(start -0.508 0.9398)
			(end 0.508 -0.9398)
			(stroke
				(width 0)
				(type default)
			)
			(fill no)
			(layer "F.CrtYd")
		)
		(fp_rect
			(start -0.508 0.9398)
			(end 0.508 -0.9398)
			(stroke
				(width 0)
				(type default)
			)
			(fill no)
			(layer "F.Fab")
		)
		(pad "1" smd custom
			(at 0 -0.4445 90)
			(size 0.1397 0.1397)
			(layers "F.Cu" "F.Mask" "F.Paste")
			(net "P3V3")
			(options
				(clearance outline)
				(anchor circle)
			)
			(primitives
				(gr_poly
					(pts
						(arc
							(start -0.1778 -0.2794)
							(mid -0.249642 -0.249642)
							(end -0.2794 -0.1778)
						)
						(arc
							(start -0.2794 0.1778)
							(mid -0.249642 0.249642)
							(end -0.1778 0.2794)
						)
						(arc
							(start 0.1778 0.2794)
							(mid 0.249642 0.249642)
							(end 0.2794 0.1778)
						)
						(arc
							(start 0.2794 -0.1778)
							(mid 0.249642 -0.249642)
							(end 0.1778 -0.2794)
						)
					)
					(width 0)
					(fill yes)
				)
			)
		)
		(pad "2" smd custom
			(at 0 0.4445 90)
			(size 0.1397 0.1397)
			(layers "F.Cu" "F.Mask" "F.Paste")
			(net "THERMHOT#")
			(options
				(clearance outline)
				(anchor circle)
			)
			(primitives
				(gr_poly
					(pts
						(arc
							(start -0.1778 -0.2794)
							(mid -0.249642 -0.249642)
							(end -0.2794 -0.1778)
						)
						(arc
							(start -0.2794 0.1778)
							(mid -0.249642 0.249642)
							(end -0.1778 0.2794)
						)
						(arc
							(start 0.1778 0.2794)
							(mid 0.249642 0.249642)
							(end 0.2794 0.1778)
						)
						(arc
							(start 0.2794 -0.1778)
							(mid 0.249642 -0.249642)
							(end 0.1778 -0.2794)
						)
					)
					(width 0)
					(fill yes)
				)
			)
		)
	)
)
